# T6G (Grand Teton) — schematic netlist excerpt (pin names and nets, part order shuffled) for the footprints in the layout excerpt that follows; sources: Cadence DE-HDL packaged netlist, KiCad conversion of 04192023_DAF0TMB3IC0_F0TG_MB_C_brd_V02_OCP.brd

R702  Q_RES  10K 5% EMPTY  pkg 0402LF  page 78 : A = PWRGD_CPU0_PWROK ; B = GND
C1170  Q_CAP  10UF 16V 10% X6S  pkg C0805  page 188 : A = P5V_AUX ; B = GND
R8028  Q_RES  4.7K 5% CHIP  pkg 0402LF  page 256 : A = P3V3_AUX ; B = LED_P12V_SCM_FAULT_D1

(kicad_pcb
	(version 20260206)
	(generator "pcbnew")
	(generator_version "10.0")
	(general
		(thickness 1.6)
		(legacy_teardrops no)
	)
	(paper "A4")
	(title_block
		(title "04192023_DAF0TMB3IC0_F0TG_MB_C_brd_V02_OCP.brd")
		(comment 1 "Grand Teton / footprints 4311-4313 of 8354")
	)
	(layers
		(0 "F.Cu" signal "TOP")
		(4 "In1.Cu" signal "GND")
		(6 "In2.Cu" signal "IN1")
		(8 "In3.Cu" signal "GND1")
		(10 "In4.Cu" signal "IN2")
		(12 "In5.Cu" signal "GND2")
		(14 "In6.Cu" signal "IN3")
		(16 "In7.Cu" signal "GND3")
		(18 "In8.Cu" signal "VCC")
		(20 "In9.Cu" signal "VCC1")
		(22 "In10.Cu" signal "GND4")
		(24 "In11.Cu" signal "IN4")
		(26 "In12.Cu" signal "GND5")
		(28 "In13.Cu" signal "IN5")
		(30 "In14.Cu" signal "GND6")
		(32 "In15.Cu" signal "IN6")
		(34 "In16.Cu" signal "GND7")
		(2 "B.Cu" signal "BOTTOM")
		(9 "F.Adhes" user "F.Adhesive")
		(11 "B.Adhes" user "B.Adhesive")
		(13 "F.Paste" user "Package Geometry/Pastemask Top")
		(15 "B.Paste" user "Package Geometry/Pastemask Bottom")
		(5 "F.SilkS" user "Ref Des/Silkscreen Top")
		(7 "B.SilkS" user "Ref Des/Silkscreen Bottom")
		(1 "F.Mask" user "Board Geometry/Soldermask Top")
		(3 "B.Mask" user "Board Geometry/Soldermask Bottom")
		(17 "Dwgs.User" user "User.Drawings")
		(19 "Cmts.User" user "User.Comments")
		(21 "Eco1.User" user "User.Eco1")
		(23 "Eco2.User" user "User.Eco2")
		(25 "Edge.Cuts" user "Board Geometry/Outline")
		(27 "Margin" user)
		(31 "F.CrtYd" user "Package Geometry/Place Bound Top")
		(29 "B.CrtYd" user "Package Geometry/Place Bound Bottom")
		(35 "F.Fab" user "Ref Des/Assembly Top")
		(33 "B.Fab" user "Ref Des/Assembly Bottom")
	)
	(footprint ""
		(layer "F.Cu")
		(at 192.037716 -57.963054 180)
		(property "Reference" "R8028"
			(at 0 0 180)
			(layer "F.SilkS")
			(hide yes)
			(effects
				(font
					(size 1.27 1.27)
				)
			)
		)
		(property "Value" ""
			(at 0 0 180)
			(layer "F.Fab")
			(effects
				(font
					(size 1.27 1.27)
				)
			)
		)
		(duplicate_pad_numbers_are_jumpers no)
		(fp_line
			(start 0.7874 0.4064)
			(end -0.7874 0.4064)
			(stroke
				(width 0.1524)
				(type default)
			)
			(layer "F.SilkS")
		)
		(fp_line
			(start 0.7874 -0.4064)
			(end 0.7874 0.4064)
			(stroke
				(width 0.1524)
				(type default)
			)
			(layer "F.SilkS")
		)
		(fp_line
			(start -0.7874 0.4064)
			(end -0.7874 -0.4064)
			(stroke
				(width 0.1524)
				(type default)
			)
			(layer "F.SilkS")
		)
		(fp_line
			(start -0.7874 -0.4064)
			(end 0.7874 -0.4064)
			(stroke
				(width 0.1524)
				(type default)
			)
			(layer "F.SilkS")
		)
		(fp_line
			(start 0.67945 0.3048)
			(end 0.120396 0.3048)
			(stroke
				(width 0.1)
				(type default)
			)
			(layer "F.Fab")
		)
		(fp_line
			(start 0.67945 -0.3048)
			(end 0.67945 0.3048)
			(stroke
				(width 0.1)
				(type default)
			)
			(layer "F.Fab")
		)
		(fp_line
			(start 0.12065 -0.2794)
			(end 0.12065 -0.3048)
			(stroke
				(width 0.1)
				(type default)
			)
			(layer "F.Fab")
		)
		(fp_line
			(start 0.12065 -0.3048)
			(end 0.67945 -0.3048)
			(stroke
				(width 0.1)
				(type default)
			)
			(layer "F.Fab")
		)
		(fp_line
			(start 0.120396 0.3048)
			(end 0.120396 0.2794)
			(stroke
				(width 0.1)
				(type default)
			)
			(layer "F.Fab")
		)
		(fp_line
			(start 0.120396 0.2794)
			(end -0.12065 0.2794)
			(stroke
				(width 0.1)
				(type default)
			)
			(layer "F.Fab")
		)
		(fp_line
			(start -0.12065 0.3048)
			(end -0.67945 0.3048)
			(stroke
				(width 0.1)
				(type default)
			)
			(layer "F.Fab")
		)
		(fp_line
			(start -0.12065 0.2794)
			(end -0.12065 0.3048)
			(stroke
				(width 0.1)
				(type default)
			)
			(layer "F.Fab")
		)
		(fp_line
			(start -0.12065 -0.2794)
			(end 0.12065 -0.2794)
			(stroke
				(width 0.1)
				(type default)
			)
			(layer "F.Fab")
		)
		(fp_line
			(start -0.12065 -0.305054)
			(end -0.12065 -0.2794)
			(stroke
				(width 0.1)
				(type default)
			)
			(layer "F.Fab")
		)
		(fp_line
			(start -0.67945 0.3048)
			(end -0.67945 -0.305054)
			(stroke
				(width 0.1)
				(type default)
			)
			(layer "F.Fab")
		)
		(fp_line
			(start -0.67945 -0.305054)
			(end -0.12065 -0.305054)
			(stroke
				(width 0.1)
				(type default)
			)
			(layer "F.Fab")
		)
		(pad "1" smd circle
			(at -0.40005 0 180)
			(size 0 0)
			(layers "F.Cu" "F.Mask" "F.Paste")
			(net "P3V3_AUX")
		)
		(pad "2" smd circle
			(at 0.40005 0 180)
			(size 0 0)
			(layers "F.Cu" "F.Mask" "F.Paste")
			(net "LED_P12V_SCM_FAULT_D1")
		)
	)
	(footprint ""
		(layer "F.Cu")
		(at 391.082022 -137.061702 -90)
		(property "Reference" "R702"
			(at 0 0 270)
			(layer "F.SilkS")
			(hide yes)
			(effects
				(font
					(size 1.27 1.27)
				)
			)
		)
		(property "Value" ""
			(at 0 0 270)
			(layer "F.Fab")
			(effects
				(font
					(size 1.27 1.27)
				)
			)
		)
		(duplicate_pad_numbers_are_jumpers no)
		(fp_line
			(start -0.7874 0.4064)
			(end -0.7874 -0.4064)
			(stroke
				(width 0.1524)
				(type default)
			)
			(layer "F.SilkS")
		)
		(fp_line
			(start 0.7874 0.4064)
			(end -0.7874 0.4064)
			(stroke
				(width 0.1524)
				(type default)
			)
			(layer "F.SilkS")
		)
		(fp_line
			(start -0.7874 -0.4064)
			(end 0.7874 -0.4064)
			(stroke
				(width 0.1524)
				(type default)
			)
			(layer "F.SilkS")
		)
		(fp_line
			(start 0.7874 -0.4064)
			(end 0.7874 0.4064)
			(stroke
				(width 0.1524)
				(type default)
			)
			(layer "F.SilkS")
		)
		(fp_line
			(start -0.67945 0.3048)
			(end -0.67945 -0.305054)
			(stroke
				(width 0.1)
				(type default)
			)
			(layer "F.Fab")
		)
		(fp_line
			(start -0.12065 0.3048)
			(end -0.67945 0.3048)
			(stroke
				(width 0.1)
				(type default)
			)
			(layer "F.Fab")
		)
		(fp_line
			(start 0.120396 0.3048)
			(end 0.120396 0.2794)
			(stroke
				(width 0.1)
				(type default)
			)
			(layer "F.Fab")
		)
		(fp_line
			(start 0.67945 0.3048)
			(end 0.120396 0.3048)
			(stroke
				(width 0.1)
				(type default)
			)
			(layer "F.Fab")
		)
		(fp_line
			(start -0.12065 0.2794)
			(end -0.12065 0.3048)
			(stroke
				(width 0.1)
				(type default)
			)
			(layer "F.Fab")
		)
		(fp_line
			(start 0.120396 0.2794)
			(end -0.12065 0.2794)
			(stroke
				(width 0.1)
				(type default)
			)
			(layer "F.Fab")
		)
		(fp_line
			(start -0.12065 -0.2794)
			(end 0.12065 -0.2794)
			(stroke
				(width 0.1)
				(type default)
			)
			(layer "F.Fab")
		)
		(fp_line
			(start 0.12065 -0.2794)
			(end 0.12065 -0.3048)
			(stroke
				(width 0.1)
				(type default)
			)
			(layer "F.Fab")
		)
		(fp_line
			(start 0.12065 -0.3048)
			(end 0.67945 -0.3048)
			(stroke
				(width 0.1)
				(type default)
			)
			(layer "F.Fab")
		)
		(fp_line
			(start 0.67945 -0.3048)
			(end 0.67945 0.3048)
			(stroke
				(width 0.1)
				(type default)
			)
			(layer "F.Fab")
		)
		(fp_line
			(start -0.67945 -0.305054)
			(end -0.12065 -0.305054)
			(stroke
				(width 0.1)
				(type default)
			)
			(layer "F.Fab")
		)
		(fp_line
			(start -0.12065 -0.305054)
			(end -0.12065 -0.2794)
			(stroke
				(width 0.1)
				(type default)
			)
			(layer "F.Fab")
		)
		(pad "1" smd circle
			(at -0.40005 0 270)
			(size 0 0)
			(layers "F.Cu" "F.Mask" "F.Paste")
			(net "PWRGD_CPU0_PWROK")
		)
		(pad "2" smd circle
			(at 0.40005 0 270)
			(size 0 0)
			(layers "F.Cu" "F.Mask" "F.Paste")
			(net "GND")
		)
	)
	(footprint ""
		(layer "F.Cu")
		(at 405.764746 -142.871952 -90)
		(property "Reference" "C1170"
			(at 0 0 270)
			(layer "F.SilkS")
			(hide yes)
			(effects
				(font
					(size 1.27 1.27)
				)
			)
		)
		(property "Value" ""
			(at 0 0 270)
			(layer "F.Fab")
			(effects
				(font
					(size 1.27 1.27)
				)
			)
		)
		(duplicate_pad_numbers_are_jumpers no)
		(fp_line
			(start -1.524 0.762)
			(end -1.524 -0.762)
			(stroke
				(width 0.1524)
				(type default)
			)
			(layer "F.SilkS")
		)
		(fp_line
			(start 1.524 0.762)
			(end -1.524 0.762)
			(stroke
				(width 0.1524)
				(type default)
			)
			(layer "F.SilkS")
		)
		(fp_line
			(start -1.524 -0.762)
			(end 1.524 -0.762)
			(stroke
				(width 0.1524)
				(type default)
			)
			(layer "F.SilkS")
		)
		(fp_line
			(start 1.524 -0.762)
			(end 1.524 0.762)
			(stroke
				(width 0.1524)
				(type default)
			)
			(layer "F.SilkS")
		)
		(fp_line
			(start -1.1049 0.724916)
			(end 1.1049 0.724916)
			(stroke
				(width 0.1)
				(type default)
			)
			(layer "F.Fab")
		)
		(fp_line
			(start 1.1049 0.724916)
			(end 1.1049 -0.724916)
			(stroke
				(width 0.1)
				(type default)
			)
			(layer "F.Fab")
		)
		(fp_line
			(start -1.1049 -0.724916)
			(end -1.1049 0.724916)
			(stroke
				(width 0.1)
				(type default)
			)
			(layer "F.Fab")
		)
		(fp_line
			(start 1.1049 -0.724916)
			(end -1.1049 -0.724916)
			(stroke
				(width 0.1)
				(type default)
			)
			(layer "F.Fab")
		)
		(pad "1" smd rect
			(at -0.889 0 90)
			(size 1.016 1.27)
			(layers "F.Cu" "F.Mask" "F.Paste")
			(net "P5V_AUX")
		)
		(pad "2" smd rect
			(at 0.889 0 90)
			(size 1.016 1.27)
			(layers "F.Cu" "F.Mask" "F.Paste")
			(net "GND")
		)
	)
)
